(kicad_pcb
	(version 20260206)
	(generator "pcbnew")
	(generator_version "10.0")
	(general
		(thickness 1.6)
		(legacy_teardrops no)
	)
	(paper "A4")
	(title_block
		(title "netronome-mezz — pcbd0082-001_rev01_jul9_a.brd")
		(comment 1 "Open CloudServer (Microsoft) / footprints 242-245 of 714")
	)
	(layers
		(0 "F.Cu" signal "TOP")
		(4 "In1.Cu" signal "02_GND")
		(6 "In2.Cu" signal "03_SIG")
		(8 "In3.Cu" signal "04_SIG")
		(10 "In4.Cu" signal "05_GND")
		(12 "In5.Cu" signal "06_PWR1")
		(14 "In6.Cu" signal "07_SIG")
		(16 "In7.Cu" signal "08_SIG")
		(18 "In8.Cu" signal "09_GND")
		(2 "B.Cu" signal "BOTTOM")
		(9 "F.Adhes" user "F.Adhesive")
		(11 "B.Adhes" user "B.Adhesive")
		(13 "F.Paste" user "Package Geometry/Pastemask Top")
		(15 "B.Paste" user "Package Geometry/Pastemask Bottom")
		(5 "F.SilkS" user "Ref Des/Silkscreen Top")
		(7 "B.SilkS" user "Ref Des/Silkscreen Bottom")
		(1 "F.Mask" user "Board Geometry/Soldermask Top")
		(3 "B.Mask" user "Board Geometry/Soldermask Bottom")
		(17 "Dwgs.User" user "User.Drawings")
		(19 "Cmts.User" user "User.Comments")
		(21 "Eco1.User" user "User.Eco1")
		(23 "Eco2.User" user "User.Eco2")
		(25 "Edge.Cuts" user "Board Geometry/Outline")
		(27 "Margin" user)
		(31 "F.CrtYd" user "Package Geometry/Place Bound Top")
		(29 "B.CrtYd" user "Package Geometry/Place Bound Bottom")
		(35 "F.Fab" user "Ref Des/Assembly Top")
		(33 "B.Fab" user "Ref Des/Assembly Bottom")
		(45 "User.4" user "COMPVAL_TYPE_BOTTOM")
	)
	(footprint ""
		(layer "F.Cu")
		(at 44.831 43.307)
		(property "Reference" "C59"
			(at 0.28067 -2.794 90)
			(unlocked yes)
			(layer "F.SilkS")
			(effects
				(font
					(size 0.7874 0.5842)
					(thickness 0.127)
				)
				(justify left)
			)
		)
		(property "Value" "100UF"
			(at -0.78232 0.4826 90)
			(unlocked yes)
			(layer "F.Fab")
			(hide yes)
			(effects
				(font
					(size 1.27 0.9652)
					(thickness 0.000001)
				)
				(justify left)
			)
		)
		(property "Device Type" "CAPC0087"
			(at -0.78232 0.4826 90)
			(unlocked yes)
			(layer "F.Fab")
			(hide yes)
			(effects
				(font
					(size 1.27 0.9652)
					(thickness 0.000001)
				)
				(justify left)
			)
		)
		(duplicate_pad_numbers_are_jumpers no)
		(fp_circle
			(center 0 0)
			(end 0.508 0)
			(stroke
				(width 0.2032)
				(type default)
			)
			(fill no)
			(layer "F.SilkS")
		)
		(fp_circle
			(center 0 0)
			(end 0.508 0)
			(stroke
				(width 0.2032)
				(type default)
			)
			(fill no)
			(layer "F.SilkS")
		)
		(fp_poly
			(pts
				(xy -1.27 2.9464) (xy 1.27 2.9464) (xy 1.27 -2.9464) (xy -1.27 -2.9464)
			)
			(stroke
				(width 0)
				(type default)
			)
			(fill no)
			(layer "F.CrtYd")
		)
		(fp_line
			(start -1.016 -2.794)
			(end 1.016 -2.794)
			(stroke
				(width 0.0254)
				(type default)
			)
			(layer "F.Fab")
		)
		(fp_line
			(start -1.016 2.794)
			(end -1.016 -2.794)
			(stroke
				(width 0.0254)
				(type default)
			)
			(layer "F.Fab")
		)
		(fp_line
			(start 1.016 -2.794)
			(end 1.016 2.794)
			(stroke
				(width 0.0254)
				(type default)
			)
			(layer "F.Fab")
		)
		(fp_line
			(start 1.016 2.794)
			(end -1.016 2.794)
			(stroke
				(width 0.0254)
				(type default)
			)
			(layer "F.Fab")
		)
		(pad "1" smd rect
			(at 0 -1.6764)
			(size 1.524 1.524)
			(layers "F.Cu" "F.Mask" "F.Paste")
			(net "VDD_CORE")
		)
		(pad "2" smd rect
			(at 0 1.6764)
			(size 1.524 1.524)
			(layers "F.Cu" "F.Mask" "F.Paste")
			(net "GND")
		)
		(zone
			(layer "F.Cu")
			(hatch none 0.5)
			(connect_pads
				(clearance 0)
			)
			(min_thickness 0.25)
			(keepout
				(tracks not_allowed)
				(vias allowed)
				(pads allowed)
				(copperpour not_allowed)
				(footprints allowed)
			)
			(placement
				(enabled no)
				(sheetname "")
			)
			(fill
				(thermal_gap 0.5)
				(thermal_bridge_width 0.5)
				(island_removal_mode 0)
			)
			(polygon
				(pts
					(xy 44.0436 42.418) (xy 45.6184 42.418) (xy 45.6184 42.5704) (xy 44.0436 42.5704)
				)
			)
		)
		(zone
			(layer "F.Cu")
			(hatch none 0.5)
			(connect_pads
				(clearance 0)
			)
			(min_thickness 0.25)
			(keepout
				(tracks not_allowed)
				(vias allowed)
				(pads allowed)
				(copperpour not_allowed)
				(footprints allowed)
			)
			(placement
				(enabled no)
				(sheetname "")
			)
			(fill
				(thermal_gap 0.5)
				(thermal_bridge_width 0.5)
				(island_removal_mode 0)
			)
			(polygon
				(pts
					(xy 44.0436 44.0436) (xy 45.6184 44.0436) (xy 45.6184 44.196) (xy 44.0436 44.196)
				)
			)
		)
		(zone
			(layer "F.Cu")
			(hatch none 0.5)
			(connect_pads
				(clearance 0)
			)
			(min_thickness 0.25)
			(keepout
				(tracks allowed)
				(vias not_allowed)
				(pads allowed)
				(copperpour not_allowed)
				(footprints allowed)
			)
			(placement
				(enabled no)
				(sheetname "")
			)
			(fill
				(thermal_gap 0.5)
				(thermal_bridge_width 0.5)
				(island_removal_mode 0)
			)
			(polygon
				(pts
					(xy 44.0436 44.9072) (xy 45.6184 44.9072) (xy 45.6184 41.7068) (xy 44.0436 41.7068)
				)
			)
		)
	)
	(footprint ""
		(layer "F.Cu")
		(at 22.987 37.592 -90)
		(property "Reference" "C142"
			(at 0.78867 5.08 0)
			(unlocked yes)
			(layer "F.SilkS")
			(effects
				(font
					(size 0.7874 0.5842)
					(thickness 0.127)
				)
				(justify left)
			)
		)
		(property "Value" "4.7UF"
			(at -0.783158 2.3876 0)
			(unlocked yes)
			(layer "F.Fab")
			(hide yes)
			(effects
				(font
					(size 1.27 0.9652)
					(thickness 0.000001)
				)
				(justify left)
			)
		)
		(property "Device Type" "CAPC0029"
			(at -0.783158 2.3876 0)
			(unlocked yes)
			(layer "F.Fab")
			(hide yes)
			(effects
				(font
					(size 1.27 0.9652)
					(thickness 0.000001)
				)
				(justify left)
			)
		)
		(duplicate_pad_numbers_are_jumpers no)
		(fp_arc
			(start -0.156058 0.0889)
			(mid -0.173617 0.045983)
			(end -0.179603 0)
			(stroke
				(width 0.2032)
				(type default)
			)
			(layer "F.SilkS")
		)
		(fp_arc
			(start -0.179603 0)
			(mid -0.173617 -0.045983)
			(end -0.156058 -0.0889)
			(stroke
				(width 0.2032)
				(type default)
			)
			(layer "F.SilkS")
		)
		(fp_arc
			(start 0.179603 0)
			(mid 0.173617 0.045983)
			(end 0.156058 0.0889)
			(stroke
				(width 0.2032)
				(type default)
			)
			(layer "F.SilkS")
		)
		(fp_arc
			(start 0.156058 -0.0889)
			(mid 0.173617 -0.045983)
			(end 0.179603 0)
			(stroke
				(width 0.2032)
				(type default)
			)
			(layer "F.SilkS")
		)
		(fp_circle
			(center 0 0)
			(end 0 -0.179603)
			(stroke
				(width 0.2032)
				(type default)
			)
			(fill no)
			(layer "F.SilkS")
		)
		(fp_poly
			(pts
				(xy -1.2192 2.3495) (xy 1.2192 2.3495) (xy 1.2192 -2.3495) (xy -1.2192 -2.3495)
			)
			(stroke
				(width 0)
				(type default)
			)
			(fill no)
			(layer "F.CrtYd")
		)
		(fp_line
			(start -0.762 1.143)
			(end -0.762 -1.143)
			(stroke
				(width 0.0254)
				(type default)
			)
			(layer "F.Fab")
		)
		(fp_line
			(start 0.762 1.143)
			(end -0.762 1.143)
			(stroke
				(width 0.0254)
				(type default)
			)
			(layer "F.Fab")
		)
		(fp_line
			(start -0.762 -1.143)
			(end 0.762 -1.143)
			(stroke
				(width 0.0254)
				(type default)
			)
			(layer "F.Fab")
		)
		(fp_line
			(start 0.762 -1.143)
			(end 0.762 1.143)
			(stroke
				(width 0.0254)
				(type default)
			)
			(layer "F.Fab")
		)
		(pad "1" smd rect
			(at 0 -1.143 270)
			(size 1.4224 1.397)
			(layers "F.Cu" "F.Mask" "F.Paste")
			(net "10N2412")
		)
		(pad "2" smd rect
			(at 0 1.143 270)
			(size 1.4224 1.397)
			(layers "F.Cu" "F.Mask" "F.Paste")
			(net "GND")
		)
		(zone
			(layer "F.Cu")
			(hatch none 0.5)
			(connect_pads
				(clearance 0)
			)
			(min_thickness 0.25)
			(keepout
				(tracks allowed)
				(vias not_allowed)
				(pads allowed)
				(copperpour not_allowed)
				(footprints allowed)
			)
			(placement
				(enabled no)
				(sheetname "")
			)
			(fill
				(thermal_gap 0.5)
				(thermal_bridge_width 0.5)
				(island_removal_mode 0)
			)
			(polygon
				(pts
					(xy 23.368 36.957) (xy 23.368 38.227) (xy 22.606 38.227) (xy 22.606 36.957)
				)
			)
		)
	)
	(footprint ""
		(layer "F.Cu")
		(at 32.639 6.35 90)
		(property "Reference" "U14"
			(at 1.016 -2.64033 90)
			(unlocked yes)
			(layer "F.SilkS")
			(effects
				(font
					(size 0.7874 0.5842)
					(thickness 0.127)
				)
				(justify left)
			)
		)
		(property "Value" "*"
			(at -0.4826 0.867842 90)
			(unlocked yes)
			(layer "F.Fab")
			(hide yes)
			(effects
				(font
					(size 1.27 0.9652)
					(thickness 0.000001)
				)
				(justify left)
			)
		)
		(property "Device Type" "ICSO0125"
			(at -0.4826 0.867893 90)
			(unlocked yes)
			(layer "F.Fab")
			(hide yes)
			(effects
				(font
					(size 1.27 0.9652)
					(thickness 0.000001)
				)
				(justify left)
			)
		)
		(duplicate_pad_numbers_are_jumpers no)
		(fp_line
			(start 2.794 -1.905)
			(end 2.794 -1.27)
			(stroke
				(width 0.1524)
				(type default)
			)
			(layer "F.SilkS")
		)
		(fp_line
			(start 2.794 -1.905)
			(end 2.794 -1.27)
			(stroke
				(width 0.1524)
				(type default)
			)
			(layer "F.SilkS")
		)
		(fp_line
			(start 1.778 -1.905)
			(end 2.794 -1.905)
			(stroke
				(width 0.1524)
				(type default)
			)
			(layer "F.SilkS")
		)
		(fp_line
			(start 1.778 -1.905)
			(end 2.794 -1.905)
			(stroke
				(width 0.1524)
				(type default)
			)
			(layer "F.SilkS")
		)
		(fp_line
			(start -1.778 -1.905)
			(end -2.794 -1.905)
			(stroke
				(width 0.1524)
				(type default)
			)
			(layer "F.SilkS")
		)
		(fp_line
			(start -1.778 -1.905)
			(end -2.794 -1.905)
			(stroke
				(width 0.1524)
				(type default)
			)
			(layer "F.SilkS")
		)
		(fp_line
			(start -2.413 -1.905)
			(end -2.794 -1.524)
			(stroke
				(width 0.1524)
				(type default)
			)
			(layer "F.SilkS")
		)
		(fp_line
			(start -2.794 -1.905)
			(end -2.794 -1.27)
			(stroke
				(width 0.1524)
				(type default)
			)
			(layer "F.SilkS")
		)
		(fp_line
			(start -2.794 -1.905)
			(end -2.794 -1.27)
			(stroke
				(width 0.1524)
				(type default)
			)
			(layer "F.SilkS")
		)
		(fp_line
			(start 2.794 1.905)
			(end 2.794 1.27)
			(stroke
				(width 0.1524)
				(type default)
			)
			(layer "F.SilkS")
		)
		(fp_line
			(start 2.794 1.905)
			(end 2.794 1.27)
			(stroke
				(width 0.1524)
				(type default)
			)
			(layer "F.SilkS")
		)
		(fp_line
			(start 1.778 1.905)
			(end 2.794 1.905)
			(stroke
				(width 0.1524)
				(type default)
			)
			(layer "F.SilkS")
		)
		(fp_line
			(start 1.778 1.905)
			(end 2.794 1.905)
			(stroke
				(width 0.1524)
				(type default)
			)
			(layer "F.SilkS")
		)
		(fp_line
			(start -1.778 1.905)
			(end -2.794 1.905)
			(stroke
				(width 0.1524)
				(type default)
			)
			(layer "F.SilkS")
		)
		(fp_line
			(start -1.778 1.905)
			(end -2.794 1.905)
			(stroke
				(width 0.1524)
				(type default)
			)
			(layer "F.SilkS")
		)
		(fp_line
			(start -2.794 1.905)
			(end -2.794 1.27)
			(stroke
				(width 0.1524)
				(type default)
			)
			(layer "F.SilkS")
		)
		(fp_line
			(start -2.794 1.905)
			(end -2.794 1.27)
			(stroke
				(width 0.1524)
				(type default)
			)
			(layer "F.SilkS")
		)
		(fp_arc
			(start -3.2258 -1.4732)
			(mid -3.046446 -1.399056)
			(end -2.971775 -1.219911)
			(stroke
				(width 0.1524)
				(type default)
			)
			(layer "F.SilkS")
		)
		(fp_arc
			(start -3.4798 -1.2192)
			(mid -3.405405 -1.398805)
			(end -3.2258 -1.4732)
			(stroke
				(width 0.1524)
				(type default)
			)
			(layer "F.SilkS")
		)
		(fp_arc
			(start -3.1877 -0.96807)
			(mid -3.206696 -0.965917)
			(end -3.2258 -0.9652)
			(stroke
				(width 0.1524)
				(type default)
			)
			(layer "F.SilkS")
		)
		(fp_arc
			(start -3.2258 -0.9652)
			(mid -3.405405 -1.039595)
			(end -3.4798 -1.2192)
			(stroke
				(width 0.1524)
				(type default)
			)
			(layer "F.SilkS")
		)
		(fp_circle
			(center -3.2258 -1.2192)
			(end -3.2258 -0.9652)
			(stroke
				(width 0.1524)
				(type default)
			)
			(fill no)
			(layer "F.SilkS")
		)
		(fp_poly
			(pts
				(xy 1.7526 -0.8636) (xy 1.7526 -0.1524) (xy 0.1524 -0.1524) (xy 0.1524 -0.8636)
			)
			(stroke
				(width 0)
				(type default)
			)
			(fill yes)
			(layer "F.Paste")
		)
		(fp_poly
			(pts
				(xy -1.7526 -0.8636) (xy -1.7526 -0.1524) (xy -0.1524 -0.1524) (xy -0.1524 -0.8636)
			)
			(stroke
				(width 0)
				(type default)
			)
			(fill yes)
			(layer "F.Paste")
		)
		(fp_poly
			(pts
				(xy 1.7526 0.8636) (xy 1.7526 0.1524) (xy 0.1524 0.1524) (xy 0.1524 0.8636)
			)
			(stroke
				(width 0)
				(type default)
			)
			(fill yes)
			(layer "F.Paste")
		)
		(fp_poly
			(pts
				(xy -1.7526 0.8636) (xy -1.7526 0.1524) (xy -0.1524 0.1524) (xy -0.1524 0.8636)
			)
			(stroke
				(width 0)
				(type default)
			)
			(fill yes)
			(layer "F.Paste")
		)
		(fp_poly
			(pts
				(xy -3.429 -2.54) (xy -3.429 2.54) (xy 3.429 2.54) (xy 3.429 -1.810487) (xy 1.859432 -1.810487)
				(xy 1.129919 -2.54)
			)
			(stroke
				(width 0)
				(type default)
			)
			(fill no)
			(layer "F.CrtYd")
		)
		(fp_line
			(start 2.5527 -1.651)
			(end -2.5527 -1.651)
			(stroke
				(width 0.1524)
				(type default)
			)
			(layer "F.Fab")
		)
		(fp_line
			(start -2.5527 -1.651)
			(end -2.5527 1.651)
			(stroke
				(width 0.1524)
				(type default)
			)
			(layer "F.Fab")
		)
		(fp_line
			(start -1.9177 -1.6383)
			(end -2.5527 -1.0033)
			(stroke
				(width 0.1524)
				(type default)
			)
			(layer "F.Fab")
		)
		(fp_line
			(start 2.5527 1.651)
			(end 2.5527 -1.651)
			(stroke
				(width 0.1524)
				(type default)
			)
			(layer "F.Fab")
		)
		(fp_line
			(start -2.5527 1.651)
			(end 2.5527 1.651)
			(stroke
				(width 0.1524)
				(type default)
			)
			(layer "F.Fab")
		)
		(fp_circle
			(center -1.9304 -0.889)
			(end -1.9304 -0.605003)
			(stroke
				(width 0.1524)
				(type default)
			)
			(fill no)
			(layer "F.Fab")
		)
		(pad "1" smd rect
			(at -2.5273 -0.750011 180)
			(size 0.2794 0.6604)
			(layers "F.Cu" "F.Mask" "F.Paste")
			(net "3N2284")
		)
		(pad "2" smd rect
			(at -2.5273 -0.250012 180)
			(size 0.2794 0.6604)
			(layers "F.Cu" "F.Mask" "F.Paste")
			(net "_NC_CLK_NC1")
		)
		(pad "3" smd rect
			(at -2.5273 0.250012 180)
			(size 0.2794 0.6604)
			(layers "F.Cu" "F.Mask" "F.Paste")
			(net "GND")
		)
		(pad "4" smd rect
			(at -2.5273 0.750011 180)
			(size 0.2794 0.6604)
			(layers "F.Cu" "F.Mask" "F.Paste")
			(net "GND")
		)
		(pad "5" smd rect
			(at -1.25001 1.6256 90)
			(size 0.2794 0.6604)
			(layers "F.Cu" "F.Mask" "F.Paste")
			(net "3N2301")
		)
		(pad "6" smd rect
			(at -0.750011 1.6256 90)
			(size 0.2794 0.6604)
			(layers "F.Cu" "F.Mask" "F.Paste")
			(net "3N2302")
		)
		(pad "7" smd rect
			(at -0.250012 1.6256 90)
			(size 0.2794 0.6604)
			(layers "F.Cu" "F.Mask" "F.Paste")
			(net "3N2290")
		)
		(pad "8" smd rect
			(at 0.250012 1.6256 90)
			(size 0.2794 0.6604)
			(layers "F.Cu" "F.Mask" "F.Paste")
			(net "3N2291")
		)
		(pad "9" smd rect
			(at 0.750011 1.6256 90)
			(size 0.2794 0.6604)
			(layers "F.Cu" "F.Mask" "F.Paste")
			(net "EXT_3.3V")
		)
		(pad "10" smd rect
			(at 1.25001 1.6256 90)
			(size 0.2794 0.6604)
			(layers "F.Cu" "F.Mask" "F.Paste")
			(net "3N2287")
		)
		(pad "11" smd rect
			(at 2.5273 0.750011 180)
			(size 0.2794 0.6604)
			(layers "F.Cu" "F.Mask" "F.Paste")
			(net "3N2285")
		)
		(pad "12" smd rect
			(at 2.5273 0.250012 180)
			(size 0.2794 0.6604)
			(layers "F.Cu" "F.Mask" "F.Paste")
			(net "_NC_CLK_NC2")
		)
		(pad "13" smd rect
			(at 2.5273 -0.250012 180)
			(size 0.2794 0.6604)
			(layers "F.Cu" "F.Mask" "F.Paste")
			(net "GND")
		)
		(pad "14" smd rect
			(at 2.5273 -0.750011 180)
			(size 0.2794 0.6604)
			(layers "F.Cu" "F.Mask" "F.Paste")
			(net "GND")
		)
		(pad "15" smd rect
			(at 1.25001 -1.6256 90)
			(size 0.2794 0.6604)
			(layers "F.Cu" "F.Mask" "F.Paste")
			(net "_NC_156M_N")
		)
		(pad "16" smd rect
			(at 0.750011 -1.6256 90)
			(size 0.2794 0.6604)
			(layers "F.Cu" "F.Mask" "F.Paste")
			(net "_NC_156M_P")
		)
		(pad "17" smd rect
			(at 0.250012 -1.6256 90)
			(size 0.2794 0.6604)
			(layers "F.Cu" "F.Mask" "F.Paste")
			(net "_NC_CLK_NC3")
		)
		(pad "18" smd rect
			(at -0.250012 -1.6256 90)
			(size 0.2794 0.6604)
			(layers "F.Cu" "F.Mask" "F.Paste")
			(net "_NC_CLK_NC4")
		)
		(pad "19" smd rect
			(at -0.750011 -1.6256 90)
			(size 0.2794 0.6604)
			(layers "F.Cu" "F.Mask" "F.Paste")
			(net "EXT_3.3V")
		)
		(pad "20" smd rect
			(at -1.25001 -1.6256 90)
			(size 0.2794 0.6604)
			(layers "F.Cu" "F.Mask" "F.Paste")
			(net "3N2286")
		)
		(pad "21" smd rect
			(at 0 0 90)
			(size 3.7846 1.9812)
			(layers "F.Cu" "F.Mask" "F.Paste")
			(net "GND")
		)
		(zone
			(layer "F.Cu")
			(hatch none 0.5)
			(connect_pads
				(clearance 0)
			)
			(min_thickness 0.25)
			(keepout
				(tracks allowed)
				(vias not_allowed)
				(pads allowed)
				(copperpour not_allowed)
				(footprints allowed)
			)
			(placement
				(enabled no)
				(sheetname "")
			)
			(fill
				(thermal_gap 0.5)
				(thermal_bridge_width 0.5)
				(island_removal_mode 0)
			)
			(polygon
				(pts
					(arc
						(start 31.75 9.5758)
						(mid 31.0896 9.5758)
						(end 31.75 9.5758)
					)
				)
			)
		)
	)
	(footprint ""
		(layer "F.Cu")
		(at 36.322 38.1 90)
		(property "Reference" "R110"
			(at 0 0 90)
			(layer "F.SilkS")
			(hide yes)
			(effects
				(font
					(size 1.27 1.27)
				)
			)
		)
		(property "Value" "10"
			(at -0.148158 1.3462 180)
			(unlocked yes)
			(layer "F.Fab")
			(hide yes)
			(effects
				(font
					(size 1.27 0.9652)
					(thickness 0.000001)
				)
				(justify left)
			)
		)
		(property "Device Type" "REST0076"
			(at -0.148158 1.3462 180)
			(unlocked yes)
			(layer "F.Fab")
			(hide yes)
			(effects
				(font
					(size 1.27 0.9652)
					(thickness 0.000001)
				)
				(justify left)
			)
		)
		(duplicate_pad_numbers_are_jumpers no)
		(fp_poly
			(pts
				(xy 0.635 1.0668) (xy 0.635 -1.0668) (xy -0.635 -1.0668) (xy -0.635 1.0668)
			)
			(stroke
				(width 0)
				(type default)
			)
			(fill no)
			(layer "F.CrtYd")
		)
		(fp_line
			(start 0.254 -0.508)
			(end 0.254 0.508)
			(stroke
				(width 0.0254)
				(type default)
			)
			(layer "F.Fab")
		)
		(fp_line
			(start -0.254 -0.508)
			(end 0.254 -0.508)
			(stroke
				(width 0.0254)
				(type default)
			)
			(layer "F.Fab")
		)
		(fp_line
			(start 0.254 0.508)
			(end -0.254 0.508)
			(stroke
				(width 0.0254)
				(type default)
			)
			(layer "F.Fab")
		)
		(fp_line
			(start -0.254 0.508)
			(end -0.254 -0.508)
			(stroke
				(width 0.0254)
				(type default)
			)
			(layer "F.Fab")
		)
		(pad "1" smd rect
			(at 0 -0.4191 90)
			(size 0.508 0.5334)
			(layers "F.Cu" "F.Mask" "F.Paste")
			(net "10N2410")
		)
		(pad "2" smd rect
			(at 0 0.4191 90)
			(size 0.508 0.5334)
			(layers "F.Cu" "F.Mask" "F.Paste")
			(net "NFP_VDD_CORE_ISEN1_N")
		)
		(zone
			(layer "F.Cu")
			(hatch none 0.5)
			(connect_pads
				(clearance 0)
			)
			(min_thickness 0.25)
			(keepout
				(tracks not_allowed)
				(vias allowed)
				(pads allowed)
				(copperpour not_allowed)
				(footprints allowed)
			)
			(placement
				(enabled no)
				(sheetname "")
			)
			(fill
				(thermal_gap 0.5)
				(thermal_bridge_width 0.5)
				(island_removal_mode 0)
			)
			(polygon
				(pts
					(xy 36.2966 38.0746) (xy 36.3474 38.0746) (xy 36.3474 38.1254) (xy 36.2966 38.1254)
				)
			)
		)
	)
)
